(kicad_pcb
	(version 20260206)
	(generator "pcbnew")
	(generator_version "10.0")
	(general
		(thickness 1.6)
		(legacy_teardrops no)
	)
	(paper "A4")
	(title_block
		(title "ptb — 12523-1.1018WZS1506.brd")
		(comment 1 "Open Vault / Knox (Wiwynn) / footprints 42-47 of 61")
	)
	(layers
		(0 "F.Cu" signal "TOP")
		(4 "In1.Cu" signal "L2GND")
		(6 "In2.Cu" signal "L3VCC")
		(2 "B.Cu" signal "BOTTOM")
		(9 "F.Adhes" user "F.Adhesive")
		(11 "B.Adhes" user "B.Adhesive")
		(13 "F.Paste" user "Package Geometry/Pastemask Top")
		(15 "B.Paste" user "Package Geometry/Pastemask Bottom")
		(5 "F.SilkS" user "Ref Des/Silkscreen Top")
		(7 "B.SilkS" user "Ref Des/Silkscreen Bottom")
		(1 "F.Mask" user "Board Geometry/Soldermask Top")
		(3 "B.Mask" user "Board Geometry/Soldermask Bottom")
		(17 "Dwgs.User" user "User.Drawings")
		(19 "Cmts.User" user "User.Comments")
		(21 "Eco1.User" user "User.Eco1")
		(23 "Eco2.User" user "User.Eco2")
		(25 "Edge.Cuts" user "Board Geometry/Outline")
		(27 "Margin" user)
		(31 "F.CrtYd" user "Package Geometry/Place Bound Top")
		(29 "B.CrtYd" user "Package Geometry/Place Bound Bottom")
		(35 "F.Fab" user "Ref Des/Assembly Top")
		(33 "B.Fab" user "Ref Des/Assembly Bottom")
	)
	(footprint ""
		(layer "F.Cu")
		(at 135.111744 -81.813908 90)
		(property "Reference" "R375"
			(at 0 0 90)
			(layer "F.SilkS")
			(hide yes)
			(effects
				(font
					(size 1.27 1.27)
				)
			)
		)
		(property "Value" "100R2F-L1-GP-U"
			(at 0.064008 -3.993896 90)
			(unlocked yes)
			(layer "F.Fab")
			(hide yes)
			(effects
				(font
					(size 1.016 1.016)
					(thickness 0.1524)
				)
			)
		)
		(property "Device Type" "R402H14"
			(at 0.064008 -5.517896 90)
			(unlocked yes)
			(layer "F.Fab")
			(hide yes)
			(effects
				(font
					(size 1.016 1.016)
					(thickness 0.1524)
				)
			)
		)
		(duplicate_pad_numbers_are_jumpers no)
		(fp_line
			(start 0.508 -0.9398)
			(end -0.508 -0.9398)
			(stroke
				(width 0.1524)
				(type default)
			)
			(layer "F.SilkS")
		)
		(fp_line
			(start -0.508 -0.9398)
			(end -0.508 0.9398)
			(stroke
				(width 0.1524)
				(type default)
			)
			(layer "F.SilkS")
		)
		(fp_rect
			(start -0.508 0.9398)
			(end 0.508 -0.9398)
			(stroke
				(width 0)
				(type default)
			)
			(fill no)
			(layer "F.CrtYd")
		)
		(fp_rect
			(start -0.508 0.9398)
			(end 0.508 -0.9398)
			(stroke
				(width 0)
				(type default)
			)
			(fill no)
			(layer "F.Fab")
		)
		(pad "1" smd custom
			(at 0 -0.4445 90)
			(size 0.1397 0.1397)
			(layers "F.Cu" "F.Mask" "F.Paste")
			(net "TRAY PRESENT_OUT_NET")
			(options
				(clearance outline)
				(anchor circle)
			)
			(primitives
				(gr_poly
					(pts
						(arc
							(start -0.1778 -0.2794)
							(mid -0.249642 -0.249642)
							(end -0.2794 -0.1778)
						)
						(arc
							(start -0.2794 0.1778)
							(mid -0.249642 0.249642)
							(end -0.1778 0.2794)
						)
						(arc
							(start 0.1778 0.2794)
							(mid 0.249642 0.249642)
							(end 0.2794 0.1778)
						)
						(arc
							(start 0.2794 -0.1778)
							(mid 0.249642 -0.249642)
							(end 0.1778 -0.2794)
						)
					)
					(width 0)
					(fill yes)
				)
			)
		)
		(pad "2" smd custom
			(at 0 0.4445 90)
			(size 0.1397 0.1397)
			(layers "F.Cu" "F.Mask" "F.Paste")
			(net "TRAY_PRESENT_OUT_NET_B")
			(options
				(clearance outline)
				(anchor circle)
			)
			(primitives
				(gr_poly
					(pts
						(arc
							(start -0.1778 -0.2794)
							(mid -0.249642 -0.249642)
							(end -0.2794 -0.1778)
						)
						(arc
							(start -0.2794 0.1778)
							(mid -0.249642 0.249642)
							(end -0.1778 0.2794)
						)
						(arc
							(start 0.1778 0.2794)
							(mid 0.249642 0.249642)
							(end 0.2794 0.1778)
						)
						(arc
							(start 0.2794 -0.1778)
							(mid 0.249642 -0.249642)
							(end 0.1778 -0.2794)
						)
					)
					(width 0)
					(fill yes)
				)
			)
		)
	)
	(footprint ""
		(layer "F.Cu")
		(at 10.962386 -95.39859)
		(property "Reference" "R486"
			(at 0 0 0)
			(layer "F.SilkS")
			(hide yes)
			(effects
				(font
					(size 1.27 1.27)
				)
			)
		)
		(property "Value" "0R2J-2-GP"
			(at 0.064008 -3.993896 0)
			(unlocked yes)
			(layer "F.Fab")
			(hide yes)
			(effects
				(font
					(size 1.016 1.016)
					(thickness 0.1524)
				)
			)
		)
		(property "Device Type" "R402H16"
			(at 0.064008 -5.517896 0)
			(unlocked yes)
			(layer "F.Fab")
			(hide yes)
			(effects
				(font
					(size 1.016 1.016)
					(thickness 0.1524)
				)
			)
		)
		(duplicate_pad_numbers_are_jumpers no)
		(fp_line
			(start -0.508 -0.9398)
			(end -0.508 0.9398)
			(stroke
				(width 0.1524)
				(type default)
			)
			(layer "F.SilkS")
		)
		(fp_line
			(start 0.508 -0.9398)
			(end -0.508 -0.9398)
			(stroke
				(width 0.1524)
				(type default)
			)
			(layer "F.SilkS")
		)
		(fp_rect
			(start -0.508 0.9398)
			(end 0.508 -0.9398)
			(stroke
				(width 0)
				(type default)
			)
			(fill no)
			(layer "F.CrtYd")
		)
		(fp_rect
			(start -0.508 0.9398)
			(end 0.508 -0.9398)
			(stroke
				(width 0)
				(type default)
			)
			(fill no)
			(layer "F.Fab")
		)
		(pad "1" smd custom
			(at 0 -0.4445)
			(size 0.1397 0.1397)
			(layers "F.Cu" "F.Mask" "F.Paste")
			(net "I2C_C_BUF_SDAOUT")
			(options
				(clearance outline)
				(anchor circle)
			)
			(primitives
				(gr_poly
					(pts
						(arc
							(start -0.1778 -0.2794)
							(mid -0.249642 -0.249642)
							(end -0.2794 -0.1778)
						)
						(arc
							(start -0.2794 0.1778)
							(mid -0.249642 0.249642)
							(end -0.1778 0.2794)
						)
						(arc
							(start 0.1778 0.2794)
							(mid 0.249642 0.249642)
							(end 0.2794 0.1778)
						)
						(arc
							(start 0.2794 -0.1778)
							(mid 0.249642 -0.249642)
							(end 0.1778 -0.2794)
						)
					)
					(width 0)
					(fill yes)
				)
			)
		)
		(pad "2" smd custom
			(at 0 0.4445)
			(size 0.1397 0.1397)
			(layers "F.Cu" "F.Mask" "F.Paste")
			(net "I2C_C_SDA")
			(options
				(clearance outline)
				(anchor circle)
			)
			(primitives
				(gr_poly
					(pts
						(arc
							(start -0.1778 -0.2794)
							(mid -0.249642 -0.249642)
							(end -0.2794 -0.1778)
						)
						(arc
							(start -0.2794 0.1778)
							(mid -0.249642 0.249642)
							(end -0.1778 0.2794)
						)
						(arc
							(start 0.1778 0.2794)
							(mid 0.249642 0.249642)
							(end 0.2794 0.1778)
						)
						(arc
							(start 0.2794 -0.1778)
							(mid 0.249642 -0.249642)
							(end 0.1778 -0.2794)
						)
					)
					(width 0)
					(fill yes)
				)
			)
		)
	)
	(footprint ""
		(layer "F.Cu")
		(at 161.159952 -18.999962 180)
		(property "Reference" "LED1"
			(at 0 0 180)
			(layer "F.SilkS")
			(hide yes)
			(effects
				(font
					(size 1.27 1.27)
				)
			)
		)
		(property "Value" "LED-G-203-GP"
			(at -2.6924 -1.4224 180)
			(unlocked yes)
			(layer "F.Fab")
			(hide yes)
			(effects
				(font
					(size 1.016 1.016)
					(thickness 0.1524)
				)
			)
		)
		(property "Device Type" "LED1608AKH26"
			(at -2.6924 -2.9464 180)
			(unlocked yes)
			(layer "F.Fab")
			(hide yes)
			(effects
				(font
					(size 1.016 1.016)
					(thickness 0.1524)
				)
			)
		)
		(duplicate_pad_numbers_are_jumpers no)
		(fp_line
			(start 0.7493 1.651)
			(end 0.7493 1.1811)
			(stroke
				(width 0.3302)
				(type default)
			)
			(layer "F.SilkS")
		)
		(fp_line
			(start 0.6604 1.3716)
			(end -0.6604 1.3716)
			(stroke
				(width 0.1524)
				(type default)
			)
			(layer "F.SilkS")
		)
		(fp_line
			(start 0.6604 -1.3716)
			(end 0.6604 1.3716)
			(stroke
				(width 0.1524)
				(type default)
			)
			(layer "F.SilkS")
		)
		(fp_line
			(start -0.5969 1.5494)
			(end 0.5842 1.5494)
			(stroke
				(width 0.508)
				(type default)
			)
			(layer "F.SilkS")
		)
		(fp_line
			(start -0.6604 1.3716)
			(end -0.6604 -1.3716)
			(stroke
				(width 0.1524)
				(type default)
			)
			(layer "F.SilkS")
		)
		(fp_line
			(start -0.6604 -1.3716)
			(end 0.6604 -1.3716)
			(stroke
				(width 0.1524)
				(type default)
			)
			(layer "F.SilkS")
		)
		(fp_line
			(start -0.7493 1.651)
			(end -0.7493 1.1811)
			(stroke
				(width 0.3302)
				(type default)
			)
			(layer "F.SilkS")
		)
		(fp_rect
			(start -0.6223 1.3335)
			(end 0.6223 -1.3335)
			(stroke
				(width 0)
				(type default)
			)
			(fill no)
			(layer "F.CrtYd")
		)
		(fp_rect
			(start -0.6223 1.3335)
			(end 0.6223 -1.3335)
			(stroke
				(width 0)
				(type default)
			)
			(fill no)
			(layer "F.Fab")
		)
		(pad "A" smd custom
			(at 0 -0.762 180)
			(size 0.2159 0.2159)
			(layers "F.Cu" "F.Mask" "F.Paste")
			(net "TPS2490_LED")
			(options
				(clearance outline)
				(anchor circle)
			)
			(primitives
				(gr_poly
					(pts
						(arc
							(start -0.3302 -0.4318)
							(mid -0.402042 -0.402042)
							(end -0.4318 -0.3302)
						)
						(arc
							(start -0.4318 0.3302)
							(mid -0.402042 0.402042)
							(end -0.3302 0.4318)
						)
						(arc
							(start 0.3302 0.4318)
							(mid 0.402042 0.402042)
							(end 0.4318 0.3302)
						)
						(arc
							(start 0.4318 -0.3302)
							(mid 0.402042 -0.402042)
							(end 0.3302 -0.4318)
						)
					)
					(width 0)
					(fill yes)
				)
			)
		)
		(pad "K" smd custom
			(at 0 0.762 180)
			(size 0.2159 0.2159)
			(layers "F.Cu" "F.Mask" "F.Paste")
			(net "GND")
			(options
				(clearance outline)
				(anchor circle)
			)
			(primitives
				(gr_poly
					(pts
						(arc
							(start -0.3302 -0.4318)
							(mid -0.402042 -0.402042)
							(end -0.4318 -0.3302)
						)
						(arc
							(start -0.4318 0.3302)
							(mid -0.402042 0.402042)
							(end -0.3302 0.4318)
						)
						(arc
							(start 0.3302 0.4318)
							(mid 0.402042 0.402042)
							(end 0.4318 0.3302)
						)
						(arc
							(start 0.4318 -0.3302)
							(mid 0.402042 -0.402042)
							(end 0.3302 -0.4318)
						)
					)
					(width 0)
					(fill yes)
				)
			)
		)
	)
	(footprint ""
		(layer "F.Cu")
		(at 136.152382 -67.048634 90)
		(property "Reference" "R387"
			(at 0 0 90)
			(layer "F.SilkS")
			(hide yes)
			(effects
				(font
					(size 1.27 1.27)
				)
			)
		)
		(property "Value" "0R2J-2-GP"
			(at 0.064008 -3.993896 90)
			(unlocked yes)
			(layer "F.Fab")
			(hide yes)
			(effects
				(font
					(size 1.016 1.016)
					(thickness 0.1524)
				)
			)
		)
		(property "Device Type" "R402H16"
			(at 0.064008 -5.517896 90)
			(unlocked yes)
			(layer "F.Fab")
			(hide yes)
			(effects
				(font
					(size 1.016 1.016)
					(thickness 0.1524)
				)
			)
		)
		(duplicate_pad_numbers_are_jumpers no)
		(fp_line
			(start 0.508 -0.9398)
			(end -0.508 -0.9398)
			(stroke
				(width 0.1524)
				(type default)
			)
			(layer "F.SilkS")
		)
		(fp_line
			(start -0.508 -0.9398)
			(end -0.508 0.9398)
			(stroke
				(width 0.1524)
				(type default)
			)
			(layer "F.SilkS")
		)
		(fp_rect
			(start -0.508 0.9398)
			(end 0.508 -0.9398)
			(stroke
				(width 0)
				(type default)
			)
			(fill no)
			(layer "F.CrtYd")
		)
		(fp_rect
			(start -0.508 0.9398)
			(end 0.508 -0.9398)
			(stroke
				(width 0)
				(type default)
			)
			(fill no)
			(layer "F.Fab")
		)
		(pad "1" smd custom
			(at 0 -0.4445 90)
			(size 0.1397 0.1397)
			(layers "F.Cu" "F.Mask" "F.Paste")
			(net "I2C_C_BUF_SCL")
			(options
				(clearance outline)
				(anchor circle)
			)
			(primitives
				(gr_poly
					(pts
						(arc
							(start -0.1778 -0.2794)
							(mid -0.249642 -0.249642)
							(end -0.2794 -0.1778)
						)
						(arc
							(start -0.2794 0.1778)
							(mid -0.249642 0.249642)
							(end -0.1778 0.2794)
						)
						(arc
							(start 0.1778 0.2794)
							(mid 0.249642 0.249642)
							(end 0.2794 0.1778)
						)
						(arc
							(start 0.2794 -0.1778)
							(mid 0.249642 -0.249642)
							(end 0.1778 -0.2794)
						)
					)
					(width 0)
					(fill yes)
				)
			)
		)
		(pad "2" smd custom
			(at 0 0.4445 90)
			(size 0.1397 0.1397)
			(layers "F.Cu" "F.Mask" "F.Paste")
			(net "I2C_C_BUF_SCL_CONN")
			(options
				(clearance outline)
				(anchor circle)
			)
			(primitives
				(gr_poly
					(pts
						(arc
							(start -0.1778 -0.2794)
							(mid -0.249642 -0.249642)
							(end -0.2794 -0.1778)
						)
						(arc
							(start -0.2794 0.1778)
							(mid -0.249642 0.249642)
							(end -0.1778 0.2794)
						)
						(arc
							(start 0.1778 0.2794)
							(mid 0.249642 0.249642)
							(end 0.2794 0.1778)
						)
						(arc
							(start 0.2794 -0.1778)
							(mid 0.249642 -0.249642)
							(end 0.1778 -0.2794)
						)
					)
					(width 0)
					(fill yes)
				)
			)
		)
	)
	(footprint ""
		(layer "F.Cu")
		(at 130.299206 -47.183548 180)
		(property "Reference" "TC5"
			(at 0 0 180)
			(layer "F.SilkS")
			(hide yes)
			(effects
				(font
					(size 1.27 1.27)
				)
			)
		)
		(property "Value" "ST68U16VDM-1-GP"
			(at 0 -9.6012 180)
			(unlocked yes)
			(layer "F.Fab")
			(hide yes)
			(effects
				(font
					(size 1.016 1.016)
					(thickness 0.1524)
				)
			)
		)
		(property "Device Type" "CT7343H79"
			(at 0 -11.1252 180)
			(unlocked yes)
			(layer "F.Fab")
			(hide yes)
			(effects
				(font
					(size 1.016 1.016)
					(thickness 0.1524)
				)
			)
		)
		(duplicate_pad_numbers_are_jumpers no)
		(fp_line
			(start 2.286 4.8768)
			(end -2.286 4.8768)
			(stroke
				(width 0.1524)
				(type default)
			)
			(layer "F.SilkS")
		)
		(fp_line
			(start 2.286 2.032)
			(end 2.286 4.8768)
			(stroke
				(width 0.1524)
				(type default)
			)
			(layer "F.SilkS")
		)
		(fp_line
			(start 2.286 -2.032)
			(end 2.286 -4.8768)
			(stroke
				(width 0.1524)
				(type default)
			)
			(layer "F.SilkS")
		)
		(fp_line
			(start 2.286 -4.8768)
			(end -2.286 -4.8768)
			(stroke
				(width 0.1524)
				(type default)
			)
			(layer "F.SilkS")
		)
		(fp_line
			(start 2.1082 -4.699)
			(end -2.1082 -4.699)
			(stroke
				(width 0.508)
				(type default)
			)
			(layer "F.SilkS")
		)
		(fp_line
			(start -2.286 4.8768)
			(end -2.286 2.032)
			(stroke
				(width 0.1524)
				(type default)
			)
			(layer "F.SilkS")
		)
		(fp_line
			(start -2.286 -4.8768)
			(end -2.286 -2.032)
			(stroke
				(width 0.1524)
				(type default)
			)
			(layer "F.SilkS")
		)
		(fp_rect
			(start -2.1463 3.6449)
			(end 2.1463 -3.6449)
			(stroke
				(width 0)
				(type default)
			)
			(fill no)
			(layer "F.CrtYd")
		)
		(fp_poly
			(pts
				(xy -2.54 4.953) (xy -2.54 4.2926) (xy -3.81 4.2926) (xy -3.81 -4.2926) (xy -2.54 -4.2926) (xy -2.54 -4.953)
				(xy 2.54 -4.953) (xy 2.54 -4.2926) (xy 3.81 -4.2926) (xy 3.81 -1.6256) (xy 2.1463 -1.6256) (xy 2.1463 -3.6449)
				(xy -2.1463 -3.6449) (xy -2.1463 3.6449) (xy 2.1463 3.6449) (xy 2.1463 -1.6129) (xy 3.81 -1.6129)
				(xy 3.81 4.2926) (xy 2.54 4.2926) (xy 2.54 4.953)
			)
			(stroke
				(width 0)
				(type default)
			)
			(fill no)
			(layer "F.CrtYd")
		)
		(fp_rect
			(start 2.54 4.2926)
			(end 3.81 -4.2926)
			(stroke
				(width 0)
				(type default)
			)
			(fill no)
			(layer "F.Fab")
		)
		(fp_rect
			(start -2.54 4.953)
			(end 2.54 -4.953)
			(stroke
				(width 0)
				(type default)
			)
			(fill no)
			(layer "F.Fab")
		)
		(fp_rect
			(start -3.81 4.2926)
			(end -2.54 -4.2926)
			(stroke
				(width 0)
				(type default)
			)
			(fill no)
			(layer "F.Fab")
		)
		(pad "1" smd rect
			(at 0 -3.1496 180)
			(size 2.413 2.286)
			(layers "F.Cu" "F.Mask" "F.Paste")
			(net "P12V")
		)
		(pad "2" smd rect
			(at 0 3.1496 180)
			(size 2.413 2.286)
			(layers "F.Cu" "F.Mask" "F.Paste")
			(net "GND")
		)
		(zone
			(layer "F.Cu")
			(hatch none 0.5)
			(connect_pads
				(clearance 0)
			)
			(min_thickness 0.25)
			(keepout
				(tracks allowed)
				(vias not_allowed)
				(pads allowed)
				(copperpour not_allowed)
				(footprints allowed)
			)
			(placement
				(enabled no)
				(sheetname "")
			)
			(fill
				(thermal_gap 0.5)
				(thermal_bridge_width 0.5)
				(island_removal_mode 0)
			)
			(polygon
				(pts
					(xy 128.787906 -45.494448) (xy 128.787906 -42.586148) (xy 131.810506 -42.586148) (xy 131.810506 -45.481748)
					(xy 131.810506 -45.811948) (xy 128.787906 -45.811948)
				)
			)
		)
		(zone
			(layer "F.Cu")
			(hatch none 0.5)
			(connect_pads
				(clearance 0)
			)
			(min_thickness 0.25)
			(keepout
				(tracks allowed)
				(vias not_allowed)
				(pads allowed)
				(copperpour not_allowed)
				(footprints allowed)
			)
			(placement
				(enabled no)
				(sheetname "")
			)
			(fill
				(thermal_gap 0.5)
				(thermal_bridge_width 0.5)
				(island_removal_mode 0)
			)
			(polygon
				(pts
					(xy 131.810506 -51.780948) (xy 128.787906 -51.780948) (xy 128.787906 -48.885348) (xy 128.787906 -48.555148)
					(xy 131.810506 -48.555148) (xy 131.810506 -48.885348)
				)
			)
		)
	)
	(footprint ""
		(layer "F.Cu")
		(at 7.659878 -15.499842)
		(property "Reference" "H3"
			(at 0 0 0)
			(layer "F.SilkS")
			(hide yes)
			(effects
				(font
					(size 1.27 1.27)
				)
			)
		)
		(property "Value" "HTE9B9R355-R-766"
			(at -8.9789 -1.1176 0)
			(unlocked yes)
			(layer "F.Fab")
			(hide yes)
			(effects
				(font
					(size 1.016 1.016)
					(thickness 0.1524)
				)
			)
		)
		(property "Device Type" "HTE9B9R355-R-766"
			(at -8.9789 -2.6416 0)
			(unlocked yes)
			(layer "F.Fab")
			(hide yes)
			(effects
				(font
					(size 1.016 1.016)
					(thickness 0.1524)
				)
			)
		)
		(duplicate_pad_numbers_are_jumpers no)
		(fp_poly
			(pts
				(arc
					(start -4.8133 0)
					(mid 4.8133 0)
					(end -4.8133 0)
				)
			)
			(stroke
				(width 0)
				(type default)
			)
			(fill no)
			(layer "B.CrtYd")
		)
		(fp_poly
			(pts
				(arc
					(start 0 -4.8133)
					(mid 4.8133 0)
					(end 0 4.8133)
				)
				(xy -7.9629 4.8133) (xy -7.9629 -4.8133)
			)
			(stroke
				(width 0)
				(type default)
			)
			(fill no)
			(layer "F.CrtYd")
		)
		(fp_poly
			(pts
				(arc
					(start -4.8133 0)
					(mid 4.8133 0)
					(end -4.8133 0)
				)
			)
			(stroke
				(width 0)
				(type default)
			)
			(fill no)
			(layer "B.Fab")
		)
		(fp_poly
			(pts
				(arc
					(start 0 -4.8133)
					(mid 4.8133 0)
					(end 0 4.8133)
				)
				(xy -7.9629 4.8133) (xy -7.9629 -4.8133)
			)
			(stroke
				(width 0)
				(type default)
			)
			(fill no)
			(layer "F.Fab")
		)
		(pad "1" thru_hole custom
			(at 0 0)
			(size 2.25425 2.25425)
			(drill 3.556)
			(layers "*.Cu" "*.Mask")
			(remove_unused_layers no)
			(net "GND")
			(clearance -3.7973)
			(thermal_gap 0.3048)
			(options
				(clearance outline)
				(anchor circle)
			)
			(primitives
				(gr_poly
					(pts
						(arc
							(start 1.5748 -4.5085)
							(mid 6.0833 0)
							(end 1.5748 4.5085)
						)
						(xy -6.0833 4.5085) (xy -6.0833 -4.5085)
					)
					(width 0)
					(fill yes)
				)
			)
			(padstack
				(mode front_inner_back)
				(layer "Inner"
					(shape circle)
					(size 3.9624 3.9624)
					(clearance 0.3048)
				)
				(layer "B.Cu"
					(shape circle)
					(size 9.017 9.017)
					(clearance -2.2225)
				)
			)
		)
	)
)
